(kicad_pcb
	(version 20260206)
	(generator "pcbnew")
	(generator_version "10.0")
	(general
		(thickness 1.6)
		(legacy_teardrops no)
	)
	(paper "A4")
	(title_block
		(title "12092022_DA0F0TYB4D0_F0T_Panel_BD_Front_D_brd_v02_OCP.brd")
		(comment 1 "Grand Teton / footprints 89-93 of 128")
	)
	(layers
		(0 "F.Cu" signal "TOP")
		(4 "In1.Cu" signal "GND")
		(6 "In2.Cu" signal "GND1")
		(2 "B.Cu" signal "BOTTOM")
		(9 "F.Adhes" user "F.Adhesive")
		(11 "B.Adhes" user "B.Adhesive")
		(13 "F.Paste" user "Package Geometry/Pastemask Top")
		(15 "B.Paste" user "Package Geometry/Pastemask Bottom")
		(5 "F.SilkS" user "Ref Des/Silkscreen Top")
		(7 "B.SilkS" user "Ref Des/Silkscreen Bottom")
		(1 "F.Mask" user "Board Geometry/Soldermask Top")
		(3 "B.Mask" user "Board Geometry/Soldermask Bottom")
		(17 "Dwgs.User" user "User.Drawings")
		(19 "Cmts.User" user "User.Comments")
		(21 "Eco1.User" user "User.Eco1")
		(23 "Eco2.User" user "User.Eco2")
		(25 "Edge.Cuts" user "Board Geometry/Outline")
		(27 "Margin" user)
		(31 "F.CrtYd" user "Package Geometry/Place Bound Top")
		(29 "B.CrtYd" user "Package Geometry/Place Bound Bottom")
		(35 "F.Fab" user "Ref Des/Assembly Top")
		(33 "B.Fab" user "Ref Des/Assembly Bottom")
	)
	(footprint ""
		(layer "F.Cu")
		(at 15.875 -48.133 180)
		(property "Reference" "R53"
			(at -2.54 -0.02667 0)
			(unlocked yes)
			(layer "F.SilkS")
			(effects
				(font
					(size 0.7874 0.5842)
					(thickness 0.1524)
				)
			)
		)
		(property "Value" ""
			(at 0 0 180)
			(layer "F.Fab")
			(effects
				(font
					(size 1.27 1.27)
				)
			)
		)
		(duplicate_pad_numbers_are_jumpers no)
		(fp_line
			(start 0.7874 0.4064)
			(end -0.7874 0.4064)
			(stroke
				(width 0.1524)
				(type default)
			)
			(layer "F.SilkS")
		)
		(fp_line
			(start 0.7874 -0.4064)
			(end 0.7874 0.4064)
			(stroke
				(width 0.1524)
				(type default)
			)
			(layer "F.SilkS")
		)
		(fp_line
			(start -0.7874 0.4064)
			(end -0.7874 -0.4064)
			(stroke
				(width 0.1524)
				(type default)
			)
			(layer "F.SilkS")
		)
		(fp_line
			(start -0.7874 -0.4064)
			(end 0.7874 -0.4064)
			(stroke
				(width 0.1524)
				(type default)
			)
			(layer "F.SilkS")
		)
		(fp_line
			(start 0.67945 0.3048)
			(end 0.120396 0.3048)
			(stroke
				(width 0.1)
				(type default)
			)
			(layer "F.Fab")
		)
		(fp_line
			(start 0.67945 -0.3048)
			(end 0.67945 0.3048)
			(stroke
				(width 0.1)
				(type default)
			)
			(layer "F.Fab")
		)
		(fp_line
			(start 0.12065 -0.2794)
			(end 0.12065 -0.3048)
			(stroke
				(width 0.1)
				(type default)
			)
			(layer "F.Fab")
		)
		(fp_line
			(start 0.12065 -0.3048)
			(end 0.67945 -0.3048)
			(stroke
				(width 0.1)
				(type default)
			)
			(layer "F.Fab")
		)
		(fp_line
			(start 0.120396 0.3048)
			(end 0.120396 0.2794)
			(stroke
				(width 0.1)
				(type default)
			)
			(layer "F.Fab")
		)
		(fp_line
			(start 0.120396 0.2794)
			(end -0.12065 0.2794)
			(stroke
				(width 0.1)
				(type default)
			)
			(layer "F.Fab")
		)
		(fp_line
			(start -0.12065 0.3048)
			(end -0.67945 0.3048)
			(stroke
				(width 0.1)
				(type default)
			)
			(layer "F.Fab")
		)
		(fp_line
			(start -0.12065 0.2794)
			(end -0.12065 0.3048)
			(stroke
				(width 0.1)
				(type default)
			)
			(layer "F.Fab")
		)
		(fp_line
			(start -0.12065 -0.2794)
			(end 0.12065 -0.2794)
			(stroke
				(width 0.1)
				(type default)
			)
			(layer "F.Fab")
		)
		(fp_line
			(start -0.12065 -0.305054)
			(end -0.12065 -0.2794)
			(stroke
				(width 0.1)
				(type default)
			)
			(layer "F.Fab")
		)
		(fp_line
			(start -0.67945 0.3048)
			(end -0.67945 -0.305054)
			(stroke
				(width 0.1)
				(type default)
			)
			(layer "F.Fab")
		)
		(fp_line
			(start -0.67945 -0.305054)
			(end -0.12065 -0.305054)
			(stroke
				(width 0.1)
				(type default)
			)
			(layer "F.Fab")
		)
		(pad "1" smd circle
			(at -0.40005 0 180)
			(size 0 0)
			(layers "F.Cu" "F.Mask" "F.Paste")
			(net "P3V3_STBY")
		)
		(pad "2" smd circle
			(at 0.40005 0 180)
			(size 0 0)
			(layers "F.Cu" "F.Mask" "F.Paste")
			(net "SMB_FRU_SCL")
		)
	)
	(footprint ""
		(layer "F.Cu")
		(at 36.703 -26.416)
		(property "Reference" "R42"
			(at -7.874 -0.35433 0)
			(unlocked yes)
			(layer "F.SilkS")
			(effects
				(font
					(size 0.7874 0.5842)
					(thickness 0.1524)
				)
			)
		)
		(property "Value" ""
			(at 0 0 0)
			(layer "F.Fab")
			(effects
				(font
					(size 1.27 1.27)
				)
			)
		)
		(duplicate_pad_numbers_are_jumpers no)
		(fp_line
			(start -0.7874 -0.4064)
			(end 0.7874 -0.4064)
			(stroke
				(width 0.1524)
				(type default)
			)
			(layer "F.SilkS")
		)
		(fp_line
			(start -0.7874 0.4064)
			(end -0.7874 -0.4064)
			(stroke
				(width 0.1524)
				(type default)
			)
			(layer "F.SilkS")
		)
		(fp_line
			(start 0.7874 -0.4064)
			(end 0.7874 0.4064)
			(stroke
				(width 0.1524)
				(type default)
			)
			(layer "F.SilkS")
		)
		(fp_line
			(start 0.7874 0.4064)
			(end -0.7874 0.4064)
			(stroke
				(width 0.1524)
				(type default)
			)
			(layer "F.SilkS")
		)
		(fp_line
			(start -0.67945 -0.305054)
			(end -0.12065 -0.305054)
			(stroke
				(width 0.1)
				(type default)
			)
			(layer "F.Fab")
		)
		(fp_line
			(start -0.67945 0.3048)
			(end -0.67945 -0.305054)
			(stroke
				(width 0.1)
				(type default)
			)
			(layer "F.Fab")
		)
		(fp_line
			(start -0.12065 -0.305054)
			(end -0.12065 -0.2794)
			(stroke
				(width 0.1)
				(type default)
			)
			(layer "F.Fab")
		)
		(fp_line
			(start -0.12065 -0.2794)
			(end 0.12065 -0.2794)
			(stroke
				(width 0.1)
				(type default)
			)
			(layer "F.Fab")
		)
		(fp_line
			(start -0.12065 0.2794)
			(end -0.12065 0.3048)
			(stroke
				(width 0.1)
				(type default)
			)
			(layer "F.Fab")
		)
		(fp_line
			(start -0.12065 0.3048)
			(end -0.67945 0.3048)
			(stroke
				(width 0.1)
				(type default)
			)
			(layer "F.Fab")
		)
		(fp_line
			(start 0.120396 0.2794)
			(end -0.12065 0.2794)
			(stroke
				(width 0.1)
				(type default)
			)
			(layer "F.Fab")
		)
		(fp_line
			(start 0.120396 0.3048)
			(end 0.120396 0.2794)
			(stroke
				(width 0.1)
				(type default)
			)
			(layer "F.Fab")
		)
		(fp_line
			(start 0.12065 -0.3048)
			(end 0.67945 -0.3048)
			(stroke
				(width 0.1)
				(type default)
			)
			(layer "F.Fab")
		)
		(fp_line
			(start 0.12065 -0.2794)
			(end 0.12065 -0.3048)
			(stroke
				(width 0.1)
				(type default)
			)
			(layer "F.Fab")
		)
		(fp_line
			(start 0.67945 -0.3048)
			(end 0.67945 0.3048)
			(stroke
				(width 0.1)
				(type default)
			)
			(layer "F.Fab")
		)
		(fp_line
			(start 0.67945 0.3048)
			(end 0.120396 0.3048)
			(stroke
				(width 0.1)
				(type default)
			)
			(layer "F.Fab")
		)
		(pad "1" smd circle
			(at -0.40005 0)
			(size 0 0)
			(layers "F.Cu" "F.Mask" "F.Paste")
			(net "NCP380_ILIM")
		)
		(pad "2" smd circle
			(at 0.40005 0)
			(size 0 0)
			(layers "F.Cu" "F.Mask" "F.Paste")
			(net "GND")
		)
	)
	(footprint ""
		(layer "F.Cu")
		(at 9.906 -49.149)
		(property "Reference" "U9"
			(at 0.508 -3.14833 0)
			(unlocked yes)
			(layer "F.SilkS")
			(effects
				(font
					(size 0.7874 0.5842)
					(thickness 0.1524)
				)
				(justify left)
			)
		)
		(property "Value" ""
			(at 0 0 0)
			(layer "F.Fab")
			(effects
				(font
					(size 1.27 1.27)
				)
			)
		)
		(duplicate_pad_numbers_are_jumpers no)
		(fp_line
			(start -1.796796 -2.500122)
			(end -1.796796 2.500122)
			(stroke
				(width 0.1524)
				(type default)
			)
			(layer "F.SilkS")
		)
		(fp_line
			(start -1.796796 2.500122)
			(end 1.796796 2.500122)
			(stroke
				(width 0.1524)
				(type default)
			)
			(layer "F.SilkS")
		)
		(fp_line
			(start -0.976122 -2.500122)
			(end -1.796796 -2.500122)
			(stroke
				(width 0.1524)
				(type default)
			)
			(layer "F.SilkS")
		)
		(fp_line
			(start 0 -1.524)
			(end -0.976122 -2.500122)
			(stroke
				(width 0.1524)
				(type default)
			)
			(layer "F.SilkS")
		)
		(fp_line
			(start 0.976122 -2.500122)
			(end 0 -1.524)
			(stroke
				(width 0.1524)
				(type default)
			)
			(layer "F.SilkS")
		)
		(fp_line
			(start 1.796796 -2.500122)
			(end 0.976122 -2.500122)
			(stroke
				(width 0.1524)
				(type default)
			)
			(layer "F.SilkS")
		)
		(fp_line
			(start 1.796796 2.500122)
			(end 1.796796 -2.500122)
			(stroke
				(width 0.1524)
				(type default)
			)
			(layer "F.SilkS")
		)
		(fp_poly
			(pts
				(xy -1.916176 -3.387852) (xy -2.932176 -3.387852) (xy -2.424176 -2.371852)
			)
			(stroke
				(width 0)
				(type default)
			)
			(fill yes)
			(layer "F.SilkS")
		)
		(fp_line
			(start -1.999996 -2.500122)
			(end -1.999996 2.500122)
			(stroke
				(width 0.1)
				(type default)
			)
			(layer "F.Fab")
		)
		(fp_line
			(start -1.999996 2.500122)
			(end 1.999996 2.500122)
			(stroke
				(width 0.1)
				(type default)
			)
			(layer "F.Fab")
		)
		(fp_line
			(start 1.999996 -2.500122)
			(end -1.999996 -2.500122)
			(stroke
				(width 0.1)
				(type default)
			)
			(layer "F.Fab")
		)
		(fp_line
			(start 1.999996 2.500122)
			(end 1.999996 -2.500122)
			(stroke
				(width 0.1)
				(type default)
			)
			(layer "F.Fab")
		)
		(fp_poly
			(pts
				(xy -4.5974 -2.413) (xy -4.5974 -1.397) (xy -3.5814 -1.905)
			)
			(stroke
				(width 0)
				(type default)
			)
			(fill yes)
			(layer "F.Fab")
		)
		(pad "1" smd rect
			(at -2.649982 -1.905 270)
			(size 0.6096 1.4224)
			(layers "F.Cu" "F.Mask" "F.Paste")
			(net "PD_FRU_A0")
		)
		(pad "2" smd rect
			(at -2.649982 -0.635 270)
			(size 0.6096 1.4224)
			(layers "F.Cu" "F.Mask" "F.Paste")
			(net "PD_FRU_A1")
		)
		(pad "3" smd rect
			(at -2.649982 0.635 270)
			(size 0.6096 1.4224)
			(layers "F.Cu" "F.Mask" "F.Paste")
			(net "PD_FRU_A2")
		)
		(pad "4" smd rect
			(at -2.649982 1.905 270)
			(size 0.6096 1.4224)
			(layers "F.Cu" "F.Mask" "F.Paste")
			(net "GND")
		)
		(pad "5" smd rect
			(at 2.649982 1.905 270)
			(size 0.6096 1.4224)
			(layers "F.Cu" "F.Mask" "F.Paste")
			(net "SMB_FRU_SDA")
		)
		(pad "6" smd rect
			(at 2.649982 0.635 270)
			(size 0.6096 1.4224)
			(layers "F.Cu" "F.Mask" "F.Paste")
			(net "SMB_FRU_SCL")
		)
		(pad "7" smd rect
			(at 2.649982 -0.635 270)
			(size 0.6096 1.4224)
			(layers "F.Cu" "F.Mask" "F.Paste")
			(net "PD_FRU_WP")
		)
		(pad "8" smd rect
			(at 2.649982 -1.905 270)
			(size 0.6096 1.4224)
			(layers "F.Cu" "F.Mask" "F.Paste")
			(net "P3V3_STBY")
		)
	)
	(footprint ""
		(layer "F.Cu")
		(at 26.67 -59.563)
		(property "Reference" ""
			(at 0 0 0)
			(layer "F.SilkS")
			(hide yes)
			(effects
				(font
					(size 1.27 1.27)
				)
			)
		)
		(property "Value" ""
			(at 0 0 0)
			(layer "F.Fab")
			(effects
				(font
					(size 1.27 1.27)
				)
			)
		)
		(duplicate_pad_numbers_are_jumpers no)
		(pad "1" smd circle
			(at 0 0)
			(size 0.9906 0.9906)
			(layers "F.Cu" "F.Mask" "F.Paste")
			(net "Net_6")
		)
		(zone
			(layer "F.Cu")
			(hatch none 0.5)
			(connect_pads
				(clearance 0)
			)
			(min_thickness 0.25)
			(keepout
				(tracks not_allowed)
				(vias allowed)
				(pads allowed)
				(copperpour not_allowed)
				(footprints allowed)
			)
			(placement
				(enabled no)
				(sheetname "")
			)
			(fill
				(thermal_gap 0.5)
				(thermal_bridge_width 0.5)
				(island_removal_mode 0)
			)
			(polygon
				(pts
					(arc
						(start 28.2956 -59.563)
						(mid 25.0444 -59.563)
						(end 28.2956 -59.563)
					)
				)
			)
		)
	)
	(footprint ""
		(layer "F.Cu")
		(at 3.048 -26.289)
		(property "Reference" "R5"
			(at -1.905 0.02667 0)
			(unlocked yes)
			(layer "F.SilkS")
			(effects
				(font
					(size 0.7874 0.5842)
					(thickness 0.1524)
				)
			)
		)
		(property "Value" ""
			(at 0 0 0)
			(layer "F.Fab")
			(effects
				(font
					(size 1.27 1.27)
				)
			)
		)
		(duplicate_pad_numbers_are_jumpers no)
		(fp_line
			(start -0.7874 -0.4064)
			(end 0.7874 -0.4064)
			(stroke
				(width 0.1524)
				(type default)
			)
			(layer "F.SilkS")
		)
		(fp_line
			(start -0.7874 0.4064)
			(end -0.7874 -0.4064)
			(stroke
				(width 0.1524)
				(type default)
			)
			(layer "F.SilkS")
		)
		(fp_line
			(start 0.7874 -0.4064)
			(end 0.7874 0.4064)
			(stroke
				(width 0.1524)
				(type default)
			)
			(layer "F.SilkS")
		)
		(fp_line
			(start 0.7874 0.4064)
			(end -0.7874 0.4064)
			(stroke
				(width 0.1524)
				(type default)
			)
			(layer "F.SilkS")
		)
		(fp_line
			(start -0.67945 -0.305054)
			(end -0.12065 -0.305054)
			(stroke
				(width 0.1)
				(type default)
			)
			(layer "F.Fab")
		)
		(fp_line
			(start -0.67945 0.3048)
			(end -0.67945 -0.305054)
			(stroke
				(width 0.1)
				(type default)
			)
			(layer "F.Fab")
		)
		(fp_line
			(start -0.12065 -0.305054)
			(end -0.12065 -0.2794)
			(stroke
				(width 0.1)
				(type default)
			)
			(layer "F.Fab")
		)
		(fp_line
			(start -0.12065 -0.2794)
			(end 0.12065 -0.2794)
			(stroke
				(width 0.1)
				(type default)
			)
			(layer "F.Fab")
		)
		(fp_line
			(start -0.12065 0.2794)
			(end -0.12065 0.3048)
			(stroke
				(width 0.1)
				(type default)
			)
			(layer "F.Fab")
		)
		(fp_line
			(start -0.12065 0.3048)
			(end -0.67945 0.3048)
			(stroke
				(width 0.1)
				(type default)
			)
			(layer "F.Fab")
		)
		(fp_line
			(start 0.120396 0.2794)
			(end -0.12065 0.2794)
			(stroke
				(width 0.1)
				(type default)
			)
			(layer "F.Fab")
		)
		(fp_line
			(start 0.120396 0.3048)
			(end 0.120396 0.2794)
			(stroke
				(width 0.1)
				(type default)
			)
			(layer "F.Fab")
		)
		(fp_line
			(start 0.12065 -0.3048)
			(end 0.67945 -0.3048)
			(stroke
				(width 0.1)
				(type default)
			)
			(layer "F.Fab")
		)
		(fp_line
			(start 0.12065 -0.2794)
			(end 0.12065 -0.3048)
			(stroke
				(width 0.1)
				(type default)
			)
			(layer "F.Fab")
		)
		(fp_line
			(start 0.67945 -0.3048)
			(end 0.67945 0.3048)
			(stroke
				(width 0.1)
				(type default)
			)
			(layer "F.Fab")
		)
		(fp_line
			(start 0.67945 0.3048)
			(end 0.120396 0.3048)
			(stroke
				(width 0.1)
				(type default)
			)
			(layer "F.Fab")
		)
		(pad "1" smd circle
			(at -0.40005 0)
			(size 0 0)
			(layers "F.Cu" "F.Mask" "F.Paste")
			(net "P3V3_STBY")
		)
		(pad "2" smd circle
			(at 0.40005 0)
			(size 0 0)
			(layers "F.Cu" "F.Mask" "F.Paste")
			(net "SYSTEM_FAULT_ID_LED_R1")
		)
	)
)
